# BASEBOARD_FAB2 (Tioga Pass) — schematic netlist excerpt (pin names and nets, part order shuffled) for the footprints in the layout excerpt that follows; sources: Cadence DE-HDL packaged netlist, KiCad conversion of Wiwynn_Tioga_Pass_MB.brd

C7C15  CAP  15.0PF 50V 5% COG  pkg 0402LF  page 114 : A = XTAL_33K_RTC2 ; B = GND
R2T44  RES  0.0 5% CHIP  pkg 0402  page 92 : A = H_CPU1_ERR2_G_N ; B = H_CPU_ERR2_G_R_N
C1A1  CAP  22UF 4V 20% X6S  pkg 0805LF  page 227 : A = PVDDQ_KLM ; B = GND

(kicad_pcb
	(version 20260206)
	(generator "pcbnew")
	(generator_version "10.0")
	(general
		(thickness 1.6)
		(legacy_teardrops no)
	)
	(paper "A4")
	(title_block
		(title "Wiwynn_Tioga_Pass_MB.brd")
		(comment 1 "Tioga Pass / footprints 913-915 of 4770")
	)
	(layers
		(0 "F.Cu" signal "TOP")
		(4 "In1.Cu" signal "L2GND")
		(6 "In2.Cu" signal "L3")
		(8 "In3.Cu" signal "L4GND")
		(10 "In4.Cu" signal "L5")
		(12 "In5.Cu" signal "L6GND")
		(14 "In6.Cu" signal "L7VCC")
		(16 "In7.Cu" signal "L8VCC")
		(18 "In8.Cu" signal "L9GND")
		(20 "In9.Cu" signal "L10")
		(22 "In10.Cu" signal "L11GND")
		(24 "In11.Cu" signal "L12")
		(26 "In12.Cu" signal "L13GND")
		(2 "B.Cu" signal "BOTTOM")
		(9 "F.Adhes" user "F.Adhesive")
		(11 "B.Adhes" user "B.Adhesive")
		(13 "F.Paste" user "Package Geometry/Pastemask Top")
		(15 "B.Paste" user "Package Geometry/Pastemask Bottom")
		(5 "F.SilkS" user "Ref Des/Silkscreen Top")
		(7 "B.SilkS" user "Ref Des/Silkscreen Bottom")
		(1 "F.Mask" user "Board Geometry/Soldermask Top")
		(3 "B.Mask" user "Board Geometry/Soldermask Bottom")
		(17 "Dwgs.User" user "User.Drawings")
		(19 "Cmts.User" user "User.Comments")
		(21 "Eco1.User" user "User.Eco1")
		(23 "Eco2.User" user "User.Eco2")
		(25 "Edge.Cuts" user "Board Geometry/Outline")
		(27 "Margin" user)
		(31 "F.CrtYd" user "Package Geometry/Place Bound Top")
		(29 "B.CrtYd" user "Package Geometry/Place Bound Bottom")
		(35 "F.Fab" user "Ref Des/Assembly Top")
		(33 "B.Fab" user "Ref Des/Assembly Bottom")
	)
	(footprint ""
		(layer "F.Cu")
		(at 369.062 -96.8375)
		(property "Reference" "C7C15"
			(at 0 0 0)
			(layer "F.SilkS")
			(hide yes)
			(effects
				(font
					(size 1.27 1.27)
				)
			)
		)
		(property "Value" ""
			(at 0 0 0)
			(layer "F.Fab")
			(effects
				(font
					(size 1.27 1.27)
				)
			)
		)
		(duplicate_pad_numbers_are_jumpers no)
		(fp_poly
			(pts
				(xy 0.3048 -0.1016) (xy 0.3048 0.9906) (xy -0.3048 0.9906) (xy -0.3048 -0.1016)
			)
			(stroke
				(width 0)
				(type default)
			)
			(fill no)
			(layer "F.CrtYd")
		)
		(fp_line
			(start -0.3048 -0.1016)
			(end -0.3048 0.9906)
			(stroke
				(width 0.1)
				(type default)
			)
			(layer "F.Fab")
		)
		(fp_line
			(start -0.3048 0.9906)
			(end 0.3048 0.9906)
			(stroke
				(width 0.1)
				(type default)
			)
			(layer "F.Fab")
		)
		(fp_line
			(start 0.3048 -0.1016)
			(end -0.3048 -0.1016)
			(stroke
				(width 0.1)
				(type default)
			)
			(layer "F.Fab")
		)
		(fp_line
			(start 0.3048 0.9906)
			(end 0.3048 -0.1016)
			(stroke
				(width 0.1)
				(type default)
			)
			(layer "F.Fab")
		)
		(pad "1" smd rect
			(at 0 0)
			(size 0.508 0.508)
			(layers "F.Cu" "F.Mask" "F.Paste")
			(net "XTAL_33K_RTC2")
		)
		(pad "2" smd rect
			(at 0 0.889)
			(size 0.508 0.508)
			(layers "F.Cu" "F.Mask" "F.Paste")
			(net "GND")
		)
		(zone
			(layer "F.Cu")
			(hatch none 0.5)
			(connect_pads
				(clearance 0)
			)
			(min_thickness 0.25)
			(keepout
				(tracks allowed)
				(vias not_allowed)
				(pads allowed)
				(copperpour not_allowed)
				(footprints allowed)
			)
			(placement
				(enabled no)
				(sheetname "")
			)
			(fill
				(thermal_gap 0.5)
				(thermal_bridge_width 0.5)
				(island_removal_mode 0)
			)
			(polygon
				(pts
					(xy 368.808 -96.5835) (xy 369.316 -96.5835) (xy 369.316 -96.2025) (xy 368.808 -96.2025)
				)
			)
		)
		(zone
			(layer "F.Cu")
			(hatch none 0.5)
			(connect_pads
				(clearance 0)
			)
			(min_thickness 0.25)
			(keepout
				(tracks not_allowed)
				(vias allowed)
				(pads allowed)
				(copperpour not_allowed)
				(footprints allowed)
			)
			(placement
				(enabled no)
				(sheetname "")
			)
			(fill
				(thermal_gap 0.5)
				(thermal_bridge_width 0.5)
				(island_removal_mode 0)
			)
			(polygon
				(pts
					(xy 368.808 -96.2025) (xy 369.316 -96.2025) (xy 369.316 -96.5835) (xy 368.808 -96.5835)
				)
			)
		)
	)
	(footprint ""
		(layer "F.Cu")
		(at 13.7541 -152.3111 -90)
		(property "Reference" "C1A1"
			(at 0 0 270)
			(layer "F.SilkS")
			(hide yes)
			(effects
				(font
					(size 1.27 1.27)
				)
			)
		)
		(property "Value" ""
			(at 0 0 270)
			(layer "F.Fab")
			(effects
				(font
					(size 1.27 1.27)
				)
			)
		)
		(duplicate_pad_numbers_are_jumpers no)
		(fp_poly
			(pts
				(xy -0.7239 -0.2159) (xy 0.7239 -0.2159) (xy 0.7239 1.9939) (xy -0.7239 1.9939)
			)
			(stroke
				(width 0)
				(type default)
			)
			(fill no)
			(layer "F.CrtYd")
		)
		(fp_line
			(start -0.7239 1.9939)
			(end 0.7239 1.9939)
			(stroke
				(width 0.1)
				(type default)
			)
			(layer "F.Fab")
		)
		(fp_line
			(start 0.7239 1.9939)
			(end 0.7239 -0.2159)
			(stroke
				(width 0.1)
				(type default)
			)
			(layer "F.Fab")
		)
		(fp_line
			(start -0.7239 -0.2159)
			(end -0.7239 1.9939)
			(stroke
				(width 0.1)
				(type default)
			)
			(layer "F.Fab")
		)
		(fp_line
			(start 0.7239 -0.2159)
			(end -0.7239 -0.2159)
			(stroke
				(width 0.1)
				(type default)
			)
			(layer "F.Fab")
		)
		(pad "1" smd rect
			(at 0 0 270)
			(size 1.27 1.016)
			(layers "F.Cu" "F.Mask" "F.Paste")
			(net "PVDDQ_KLM")
		)
		(pad "2" smd rect
			(at 0 1.778 270)
			(size 1.27 1.016)
			(layers "F.Cu" "F.Mask" "F.Paste")
			(net "GND")
		)
		(zone
			(layer "F.Cu")
			(hatch none 0.5)
			(connect_pads
				(clearance 0)
			)
			(min_thickness 0.25)
			(keepout
				(tracks not_allowed)
				(vias allowed)
				(pads allowed)
				(copperpour not_allowed)
				(footprints allowed)
			)
			(placement
				(enabled no)
				(sheetname "")
			)
			(fill
				(thermal_gap 0.5)
				(thermal_bridge_width 0.5)
				(island_removal_mode 0)
			)
			(polygon
				(pts
					(xy 13.2461 -152.9461) (xy 13.2461 -151.6761) (xy 12.4841 -151.6761) (xy 12.4841 -152.9461)
				)
			)
		)
	)
	(footprint ""
		(layer "F.Cu")
		(at 382.131062 -76.019406 180)
		(property "Reference" "R2T44"
			(at 0 0 180)
			(layer "F.SilkS")
			(hide yes)
			(effects
				(font
					(size 1.27 1.27)
				)
			)
		)
		(property "Value" ""
			(at 0 0 180)
			(layer "F.Fab")
			(effects
				(font
					(size 1.27 1.27)
				)
			)
		)
		(duplicate_pad_numbers_are_jumpers no)
		(fp_poly
			(pts
				(xy -0.2794 -0.1016) (xy 0.2794 -0.1016) (xy 0.2794 0.9906) (xy -0.2794 0.9906)
			)
			(stroke
				(width 0)
				(type default)
			)
			(fill no)
			(layer "F.CrtYd")
		)
		(fp_line
			(start 0.2794 0.9906)
			(end 0.2794 -0.1016)
			(stroke
				(width 0.1)
				(type default)
			)
			(layer "F.Fab")
		)
		(fp_line
			(start 0.2794 -0.1016)
			(end -0.2794 -0.1016)
			(stroke
				(width 0.1)
				(type default)
			)
			(layer "F.Fab")
		)
		(fp_line
			(start -0.2794 0.9906)
			(end 0.2794 0.9906)
			(stroke
				(width 0.1)
				(type default)
			)
			(layer "F.Fab")
		)
		(fp_line
			(start -0.2794 -0.1016)
			(end -0.2794 0.9906)
			(stroke
				(width 0.1)
				(type default)
			)
			(layer "F.Fab")
		)
		(pad "1" smd rect
			(at 0 0 180)
			(size 0.508 0.508)
			(layers "F.Cu" "F.Mask" "F.Paste")
			(net "H_CPU1_ERR2_G_N")
		)
		(pad "2" smd rect
			(at 0 0.889 180)
			(size 0.508 0.508)
			(layers "F.Cu" "F.Mask" "F.Paste")
			(net "H_CPU_ERR2_G_R_N")
		)
		(zone
			(layer "F.Cu")
			(hatch none 0.5)
			(connect_pads
				(clearance 0)
			)
			(min_thickness 0.25)
			(keepout
				(tracks not_allowed)
				(vias allowed)
				(pads allowed)
				(copperpour not_allowed)
				(footprints allowed)
			)
			(placement
				(enabled no)
				(sheetname "")
			)
			(fill
				(thermal_gap 0.5)
				(thermal_bridge_width 0.5)
				(island_removal_mode 0)
			)
			(polygon
				(pts
					(xy 382.385062 -76.654406) (xy 381.877062 -76.654406) (xy 381.877062 -76.273406) (xy 382.385062 -76.273406)
				)
			)
		)
		(zone
			(layer "F.Cu")
			(hatch none 0.5)
			(connect_pads
				(clearance 0)
			)
			(min_thickness 0.25)
			(keepout
				(tracks allowed)
				(vias not_allowed)
				(pads allowed)
				(copperpour not_allowed)
				(footprints allowed)
			)
			(placement
				(enabled no)
				(sheetname "")
			)
			(fill
				(thermal_gap 0.5)
				(thermal_bridge_width 0.5)
				(island_removal_mode 0)
			)
			(polygon
				(pts
					(xy 382.385062 -76.273406) (xy 381.877062 -76.273406) (xy 381.877062 -76.654406) (xy 382.385062 -76.654406)
				)
			)
		)
	)
)
